# S9S_MB_2U (Grand Teton) — schematic netlist excerpt (pin names and nets, part order shuffled) for the footprints in the layout excerpt that follows; sources: Cadence DE-HDL packaged netlist, KiCad conversion of 03242023_DA0F0TMBIJ0_F0T_Motherboard_J_brd_V01_OCP.brd

C1186  Q_CAP  22UF 4V 20% X6S  pkg C0603  page 189 : A = P1V8_PCH_AUX ; B = GND
R2204  Q_RES  2.2K 5% EMPTY  pkg 0402LF  page 231 : A = P3V3_AUX ; B = SMB_PCIE0_3V3AUX_SCL

(kicad_pcb
	(version 20260206)
	(generator "pcbnew")
	(generator_version "10.0")
	(general
		(thickness 1.6)
		(legacy_teardrops no)
	)
	(paper "A4")
	(title_block
		(title "03242023_DA0F0TMBIJ0_F0T_Motherboard_J_brd_V01_OCP.brd")
		(comment 1 "Grand Teton / footprints 5864-5865 of 6105")
	)
	(layers
		(0 "F.Cu" signal "TOP")
		(4 "In1.Cu" signal "GND")
		(6 "In2.Cu" signal "IN1")
		(8 "In3.Cu" signal "GND1")
		(10 "In4.Cu" signal "IN2")
		(12 "In5.Cu" signal "GND2")
		(14 "In6.Cu" signal "IN3")
		(16 "In7.Cu" signal "GND3")
		(18 "In8.Cu" signal "VCC")
		(20 "In9.Cu" signal "VCC1")
		(22 "In10.Cu" signal "GND4")
		(24 "In11.Cu" signal "IN4")
		(26 "In12.Cu" signal "GND5")
		(28 "In13.Cu" signal "IN5")
		(30 "In14.Cu" signal "GND6")
		(32 "In15.Cu" signal "IN6")
		(34 "In16.Cu" signal "GND7")
		(2 "B.Cu" signal "BOTTOM")
		(9 "F.Adhes" user "F.Adhesive")
		(11 "B.Adhes" user "B.Adhesive")
		(13 "F.Paste" user "Package Geometry/Pastemask Top")
		(15 "B.Paste" user "Package Geometry/Pastemask Bottom")
		(5 "F.SilkS" user "Ref Des/Silkscreen Top")
		(7 "B.SilkS" user "Ref Des/Silkscreen Bottom")
		(1 "F.Mask" user "Board Geometry/Soldermask Top")
		(3 "B.Mask" user "Board Geometry/Soldermask Bottom")
		(17 "Dwgs.User" user "User.Drawings")
		(19 "Cmts.User" user "User.Comments")
		(21 "Eco1.User" user "User.Eco1")
		(23 "Eco2.User" user "User.Eco2")
		(25 "Edge.Cuts" user "Board Geometry/Outline")
		(27 "Margin" user)
		(31 "F.CrtYd" user "Package Geometry/Place Bound Top")
		(29 "B.CrtYd" user "Package Geometry/Place Bound Bottom")
		(35 "F.Fab" user "Ref Des/Assembly Top")
		(33 "B.Fab" user "Ref Des/Assembly Bottom")
	)
	(footprint ""
		(layer "B.Cu")
		(at 157.0355 -8.801608 180)
		(property "Reference" "R2204"
			(at 0 0 0)
			(layer "B.SilkS")
			(hide yes)
			(effects
				(font
					(size 1.27 1.27)
				)
				(justify mirror)
			)
		)
		(property "Value" ""
			(at 0 0 0)
			(layer "B.Fab")
			(effects
				(font
					(size 1.27 1.27)
				)
				(justify mirror)
			)
		)
		(duplicate_pad_numbers_are_jumpers no)
		(fp_line
			(start 0.7874 0.4064)
			(end 0.7874 -0.4064)
			(stroke
				(width 0.1524)
				(type default)
			)
			(layer "B.SilkS")
		)
		(fp_line
			(start 0.7874 -0.4064)
			(end -0.7874 -0.4064)
			(stroke
				(width 0.1524)
				(type default)
			)
			(layer "B.SilkS")
		)
		(fp_line
			(start -0.7874 0.4064)
			(end 0.7874 0.4064)
			(stroke
				(width 0.1524)
				(type default)
			)
			(layer "B.SilkS")
		)
		(fp_line
			(start -0.7874 -0.4064)
			(end -0.7874 0.4064)
			(stroke
				(width 0.1524)
				(type default)
			)
			(layer "B.SilkS")
		)
		(fp_line
			(start 0.67945 0.3048)
			(end 0.67945 -0.305054)
			(stroke
				(width 0.1)
				(type default)
			)
			(layer "B.Fab")
		)
		(fp_line
			(start 0.67945 -0.305054)
			(end 0.12065 -0.305054)
			(stroke
				(width 0.1)
				(type default)
			)
			(layer "B.Fab")
		)
		(fp_line
			(start 0.12065 0.3048)
			(end 0.67945 0.3048)
			(stroke
				(width 0.1)
				(type default)
			)
			(layer "B.Fab")
		)
		(fp_line
			(start 0.12065 0.2794)
			(end 0.12065 0.3048)
			(stroke
				(width 0.1)
				(type default)
			)
			(layer "B.Fab")
		)
		(fp_line
			(start 0.12065 -0.2794)
			(end -0.12065 -0.2794)
			(stroke
				(width 0.1)
				(type default)
			)
			(layer "B.Fab")
		)
		(fp_line
			(start 0.12065 -0.305054)
			(end 0.12065 -0.2794)
			(stroke
				(width 0.1)
				(type default)
			)
			(layer "B.Fab")
		)
		(fp_line
			(start -0.120396 0.3048)
			(end -0.120396 0.2794)
			(stroke
				(width 0.1)
				(type default)
			)
			(layer "B.Fab")
		)
		(fp_line
			(start -0.120396 0.2794)
			(end 0.12065 0.2794)
			(stroke
				(width 0.1)
				(type default)
			)
			(layer "B.Fab")
		)
		(fp_line
			(start -0.12065 -0.2794)
			(end -0.12065 -0.3048)
			(stroke
				(width 0.1)
				(type default)
			)
			(layer "B.Fab")
		)
		(fp_line
			(start -0.12065 -0.3048)
			(end -0.67945 -0.3048)
			(stroke
				(width 0.1)
				(type default)
			)
			(layer "B.Fab")
		)
		(fp_line
			(start -0.67945 0.3048)
			(end -0.120396 0.3048)
			(stroke
				(width 0.1)
				(type default)
			)
			(layer "B.Fab")
		)
		(fp_line
			(start -0.67945 -0.3048)
			(end -0.67945 0.3048)
			(stroke
				(width 0.1)
				(type default)
			)
			(layer "B.Fab")
		)
		(pad "1" smd circle
			(at 0.40005 0)
			(size 0 0)
			(layers "B.Cu" "B.Mask" "B.Paste")
			(net "P3V3_AUX")
		)
		(pad "2" smd circle
			(at -0.40005 0)
			(size 0 0)
			(layers "B.Cu" "B.Mask" "B.Paste")
			(net "SMB_PCIE0_3V3AUX_SCL")
		)
	)
	(footprint ""
		(layer "B.Cu")
		(at 333.569056 -58.473086 -90)
		(property "Reference" "C1186"
			(at 0 0 90)
			(layer "B.SilkS")
			(hide yes)
			(effects
				(font
					(size 1.27 1.27)
				)
				(justify mirror)
			)
		)
		(property "Value" ""
			(at 0 0 90)
			(layer "B.Fab")
			(effects
				(font
					(size 1.27 1.27)
				)
				(justify mirror)
			)
		)
		(duplicate_pad_numbers_are_jumpers no)
		(fp_line
			(start -1.2954 0.5842)
			(end 1.2954 0.5842)
			(stroke
				(width 0.1524)
				(type default)
			)
			(layer "B.SilkS")
		)
		(fp_line
			(start 1.2954 0.5842)
			(end 1.2954 -0.5842)
			(stroke
				(width 0.1524)
				(type default)
			)
			(layer "B.SilkS")
		)
		(fp_line
			(start -1.2954 -0.5842)
			(end -1.2954 0.5842)
			(stroke
				(width 0.1524)
				(type default)
			)
			(layer "B.SilkS")
		)
		(fp_line
			(start 0 -0.5842)
			(end 0 0.5842)
			(stroke
				(width 0.1524)
				(type default)
			)
			(layer "B.SilkS")
		)
		(fp_line
			(start 1.2954 -0.5842)
			(end -1.2954 -0.5842)
			(stroke
				(width 0.1524)
				(type default)
			)
			(layer "B.SilkS")
		)
		(fp_line
			(start -0.8636 0.4572)
			(end 0.8636 0.4572)
			(stroke
				(width 0.1)
				(type default)
			)
			(layer "B.Fab")
		)
		(fp_line
			(start 0.8636 0.4572)
			(end 0.8636 0.4064)
			(stroke
				(width 0.1)
				(type default)
			)
			(layer "B.Fab")
		)
		(fp_line
			(start -1.1938 0.4064)
			(end -0.8636 0.4064)
			(stroke
				(width 0.1)
				(type default)
			)
			(layer "B.Fab")
		)
		(fp_line
			(start -0.8636 0.4064)
			(end -0.8636 0.4572)
			(stroke
				(width 0.1)
				(type default)
			)
			(layer "B.Fab")
		)
		(fp_line
			(start 0.8636 0.4064)
			(end 1.1938 0.4064)
			(stroke
				(width 0.1)
				(type default)
			)
			(layer "B.Fab")
		)
		(fp_line
			(start 1.1938 0.4064)
			(end 1.1938 -0.4064)
			(stroke
				(width 0.1)
				(type default)
			)
			(layer "B.Fab")
		)
		(fp_line
			(start -1.1938 -0.4064)
			(end -1.1938 0.4064)
			(stroke
				(width 0.1)
				(type default)
			)
			(layer "B.Fab")
		)
		(fp_line
			(start -0.8636 -0.4064)
			(end -1.1938 -0.4064)
			(stroke
				(width 0.1)
				(type default)
			)
			(layer "B.Fab")
		)
		(fp_line
			(start 0.8636 -0.4064)
			(end 0.8636 -0.4572)
			(stroke
				(width 0.1)
				(type default)
			)
			(layer "B.Fab")
		)
		(fp_line
			(start 1.1938 -0.4064)
			(end 0.8636 -0.4064)
			(stroke
				(width 0.1)
				(type default)
			)
			(layer "B.Fab")
		)
		(fp_line
			(start -0.8636 -0.4572)
			(end -0.8636 -0.4064)
			(stroke
				(width 0.1)
				(type default)
			)
			(layer "B.Fab")
		)
		(fp_line
			(start 0.8636 -0.4572)
			(end -0.8636 -0.4572)
			(stroke
				(width 0.1)
				(type default)
			)
			(layer "B.Fab")
		)
		(pad "1" smd rect
			(at 0.7366 0 180)
			(size 0.7112 0.8128)
			(layers "B.Cu" "B.Mask" "B.Paste")
			(net "P1V8_PCH_AUX")
		)
		(pad "2" smd rect
			(at -0.7366 0 180)
			(size 0.7112 0.8128)
			(layers "B.Cu" "B.Mask" "B.Paste")
			(net "GND")
		)
	)
)
